(kicad_pcb
	(version 20260206)
	(generator "pcbnew")
	(generator_version "10.0")
	(general
		(thickness 1.6)
		(legacy_teardrops no)
	)
	(paper "A4")
	(title_block
		(title "Wiwynn_Tioga_Pass_MB.brd")
		(comment 1 "Tioga Pass / footprint 4281 of 4770 (J9L2), pads 244-291 of 291")
	)
	(layers
		(0 "F.Cu" signal "TOP")
		(4 "In1.Cu" signal "L2GND")
		(6 "In2.Cu" signal "L3")
		(8 "In3.Cu" signal "L4GND")
		(10 "In4.Cu" signal "L5")
		(12 "In5.Cu" signal "L6GND")
		(14 "In6.Cu" signal "L7VCC")
		(16 "In7.Cu" signal "L8VCC")
		(18 "In8.Cu" signal "L9GND")
		(20 "In9.Cu" signal "L10")
		(22 "In10.Cu" signal "L11GND")
		(24 "In11.Cu" signal "L12")
		(26 "In12.Cu" signal "L13GND")
		(2 "B.Cu" signal "BOTTOM")
		(9 "F.Adhes" user "F.Adhesive")
		(11 "B.Adhes" user "B.Adhesive")
		(13 "F.Paste" user "Package Geometry/Pastemask Top")
		(15 "B.Paste" user "Package Geometry/Pastemask Bottom")
		(5 "F.SilkS" user "Ref Des/Silkscreen Top")
		(7 "B.SilkS" user "Ref Des/Silkscreen Bottom")
		(1 "F.Mask" user "Board Geometry/Soldermask Top")
		(3 "B.Mask" user "Board Geometry/Soldermask Bottom")
		(17 "Dwgs.User" user "User.Drawings")
		(19 "Cmts.User" user "User.Comments")
		(21 "Eco1.User" user "User.Eco1")
		(23 "Eco2.User" user "User.Eco2")
		(25 "Edge.Cuts" user "Board Geometry/Outline")
		(27 "Margin" user)
		(31 "F.CrtYd" user "Package Geometry/Place Bound Top")
		(29 "B.CrtYd" user "Package Geometry/Place Bound Bottom")
		(35 "F.Fab" user "Ref Des/Assembly Top")
		(33 "B.Fab" user "Ref Des/Assembly Bottom")
	)
	(footprint ""
		(layer "B.Cu")
		(at 29.699458 -142.477236 90)
		(property "Reference" "J9L2"
			(at 2.403348 38.118542 0)
			(unlocked yes)
			(layer "B.SilkS")
			(effects
				(font
					(size 0.7874 0.5842)
					(thickness 0.1524)
				)
				(justify left mirror)
			)
		)
		(property "Value" ""
			(at 0 0 90)
			(layer "B.Fab")
			(effects
				(font
					(size 1.27 1.27)
				)
				(justify mirror)
			)
		)
		(duplicate_pad_numbers_are_jumpers no)
		(pad "241" smd rect
			(at -4.59994 86.700106 270)
			(size 1.8034 0.508)
			(layers "B.Cu" "B.Mask" "B.Paste")
			(net "GND")
		)
		(pad "242" smd rect
			(at -4.59994 87.54999 270)
			(size 1.8034 0.508)
			(layers "B.Cu" "B.Mask" "B.Paste")
			(net "M_L_DQ<33>")
		)
		(pad "243" smd rect
			(at -4.59994 88.399874 270)
			(size 1.8034 0.508)
			(layers "B.Cu" "B.Mask" "B.Paste")
			(net "GND")
		)
		(pad "244" smd rect
			(at -4.59994 89.250012 270)
			(size 1.8034 0.508)
			(layers "B.Cu" "B.Mask" "B.Paste")
			(net "M_L_DQS_DN<4>")
		)
		(pad "245" smd rect
			(at -4.59994 90.099896 270)
			(size 1.8034 0.508)
			(layers "B.Cu" "B.Mask" "B.Paste")
			(net "M_L_DQS_DP<4>")
		)
		(pad "246" smd rect
			(at -4.59994 90.950034 270)
			(size 1.8034 0.508)
			(layers "B.Cu" "B.Mask" "B.Paste")
			(net "GND")
		)
		(pad "247" smd rect
			(at -4.59994 91.799918 270)
			(size 1.8034 0.508)
			(layers "B.Cu" "B.Mask" "B.Paste")
			(net "M_L_DQ<39>")
		)
		(pad "248" smd rect
			(at -4.59994 92.650056 270)
			(size 1.8034 0.508)
			(layers "B.Cu" "B.Mask" "B.Paste")
			(net "GND")
		)
		(pad "249" smd rect
			(at -4.59994 93.49994 270)
			(size 1.8034 0.508)
			(layers "B.Cu" "B.Mask" "B.Paste")
			(net "M_L_DQ<35>")
		)
		(pad "250" smd rect
			(at -4.59994 94.350078 270)
			(size 1.8034 0.508)
			(layers "B.Cu" "B.Mask" "B.Paste")
			(net "GND")
		)
		(pad "251" smd rect
			(at -4.59994 95.199962 270)
			(size 1.8034 0.508)
			(layers "B.Cu" "B.Mask" "B.Paste")
			(net "M_L_DQ<45>")
		)
		(pad "252" smd rect
			(at -4.59994 96.0501 270)
			(size 1.8034 0.508)
			(layers "B.Cu" "B.Mask" "B.Paste")
			(net "GND")
		)
		(pad "253" smd rect
			(at -4.59994 96.899984 270)
			(size 1.8034 0.508)
			(layers "B.Cu" "B.Mask" "B.Paste")
			(net "M_L_DQ<41>")
		)
		(pad "254" smd rect
			(at -4.59994 97.750122 270)
			(size 1.8034 0.508)
			(layers "B.Cu" "B.Mask" "B.Paste")
			(net "GND")
		)
		(pad "255" smd rect
			(at -4.59994 98.600006 270)
			(size 1.8034 0.508)
			(layers "B.Cu" "B.Mask" "B.Paste")
			(net "M_L_DQS_DN<5>")
		)
		(pad "256" smd rect
			(at -4.59994 99.44989 270)
			(size 1.8034 0.508)
			(layers "B.Cu" "B.Mask" "B.Paste")
			(net "M_L_DQS_DP<5>")
		)
		(pad "257" smd rect
			(at -4.59994 100.300028 270)
			(size 1.8034 0.508)
			(layers "B.Cu" "B.Mask" "B.Paste")
			(net "GND")
		)
		(pad "258" smd rect
			(at -4.59994 101.149912 270)
			(size 1.8034 0.508)
			(layers "B.Cu" "B.Mask" "B.Paste")
			(net "M_L_DQ<47>")
		)
		(pad "259" smd rect
			(at -4.59994 102.00005 270)
			(size 1.8034 0.508)
			(layers "B.Cu" "B.Mask" "B.Paste")
			(net "GND")
		)
		(pad "260" smd rect
			(at -4.59994 102.849934 270)
			(size 1.8034 0.508)
			(layers "B.Cu" "B.Mask" "B.Paste")
			(net "M_L_DQ<43>")
		)
		(pad "261" smd rect
			(at -4.59994 103.700072 270)
			(size 1.8034 0.508)
			(layers "B.Cu" "B.Mask" "B.Paste")
			(net "GND")
		)
		(pad "262" smd rect
			(at -4.59994 104.549956 270)
			(size 1.8034 0.508)
			(layers "B.Cu" "B.Mask" "B.Paste")
			(net "M_L_DQ<53>")
		)
		(pad "263" smd rect
			(at -4.59994 105.400094 270)
			(size 1.8034 0.508)
			(layers "B.Cu" "B.Mask" "B.Paste")
			(net "GND")
		)
		(pad "264" smd rect
			(at -4.59994 106.249978 270)
			(size 1.8034 0.508)
			(layers "B.Cu" "B.Mask" "B.Paste")
			(net "M_L_DQ<49>")
		)
		(pad "265" smd rect
			(at -4.59994 107.100116 270)
			(size 1.8034 0.508)
			(layers "B.Cu" "B.Mask" "B.Paste")
			(net "GND")
		)
		(pad "266" smd rect
			(at -4.59994 107.95 270)
			(size 1.8034 0.508)
			(layers "B.Cu" "B.Mask" "B.Paste")
			(net "M_L_DQS_DN<6>")
		)
		(pad "267" smd rect
			(at -4.59994 108.799884 270)
			(size 1.8034 0.508)
			(layers "B.Cu" "B.Mask" "B.Paste")
			(net "M_L_DQS_DP<6>")
		)
		(pad "268" smd rect
			(at -4.59994 109.650022 270)
			(size 1.8034 0.508)
			(layers "B.Cu" "B.Mask" "B.Paste")
			(net "GND")
		)
		(pad "269" smd rect
			(at -4.59994 110.499906 270)
			(size 1.8034 0.508)
			(layers "B.Cu" "B.Mask" "B.Paste")
			(net "M_L_DQ<55>")
		)
		(pad "270" smd rect
			(at -4.59994 111.350044 270)
			(size 1.8034 0.508)
			(layers "B.Cu" "B.Mask" "B.Paste")
			(net "GND")
		)
		(pad "271" smd rect
			(at -4.59994 112.199928 270)
			(size 1.8034 0.508)
			(layers "B.Cu" "B.Mask" "B.Paste")
			(net "M_L_DQ<51>")
		)
		(pad "272" smd rect
			(at -4.59994 113.050066 270)
			(size 1.8034 0.508)
			(layers "B.Cu" "B.Mask" "B.Paste")
			(net "GND")
		)
		(pad "273" smd rect
			(at -4.59994 113.89995 270)
			(size 1.8034 0.508)
			(layers "B.Cu" "B.Mask" "B.Paste")
			(net "M_L_DQ<61>")
		)
		(pad "274" smd rect
			(at -4.59994 114.750088 270)
			(size 1.8034 0.508)
			(layers "B.Cu" "B.Mask" "B.Paste")
			(net "GND")
		)
		(pad "275" smd rect
			(at -4.59994 115.599972 270)
			(size 1.8034 0.508)
			(layers "B.Cu" "B.Mask" "B.Paste")
			(net "M_L_DQ<57>")
		)
		(pad "276" smd rect
			(at -4.59994 116.45011 270)
			(size 1.8034 0.508)
			(layers "B.Cu" "B.Mask" "B.Paste")
			(net "GND")
		)
		(pad "277" smd rect
			(at -4.59994 117.299994 270)
			(size 1.8034 0.508)
			(layers "B.Cu" "B.Mask" "B.Paste")
			(net "M_L_DQS_DN<7>")
		)
		(pad "278" smd rect
			(at -4.59994 118.149878 270)
			(size 1.8034 0.508)
			(layers "B.Cu" "B.Mask" "B.Paste")
			(net "M_L_DQS_DP<7>")
		)
		(pad "279" smd rect
			(at -4.59994 119.000016 270)
			(size 1.8034 0.508)
			(layers "B.Cu" "B.Mask" "B.Paste")
			(net "GND")
		)
		(pad "280" smd rect
			(at -4.59994 119.8499 270)
			(size 1.8034 0.508)
			(layers "B.Cu" "B.Mask" "B.Paste")
			(net "M_L_DQ<63>")
		)
		(pad "281" smd rect
			(at -4.59994 120.700038 270)
			(size 1.8034 0.508)
			(layers "B.Cu" "B.Mask" "B.Paste")
			(net "GND")
		)
		(pad "282" smd rect
			(at -4.59994 121.549922 270)
			(size 1.8034 0.508)
			(layers "B.Cu" "B.Mask" "B.Paste")
			(net "M_L_DQ<59>")
		)
		(pad "283" smd rect
			(at -4.59994 122.40006 270)
			(size 1.8034 0.508)
			(layers "B.Cu" "B.Mask" "B.Paste")
			(net "GND")
		)
		(pad "284" smd rect
			(at -4.59994 123.249944 270)
			(size 1.8034 0.508)
			(layers "B.Cu" "B.Mask" "B.Paste")
			(net "PVPP_KLM")
		)
		(pad "285" smd rect
			(at -4.59994 124.100082 270)
			(size 1.8034 0.508)
			(layers "B.Cu" "B.Mask" "B.Paste")
			(net "SMB_DDR_KLM_VPP_SDA")
		)
		(pad "286" smd rect
			(at -4.59994 124.949966 270)
			(size 1.8034 0.508)
			(layers "B.Cu" "B.Mask" "B.Paste")
			(net "PVPP_KLM")
		)
		(pad "287" smd rect
			(at -4.59994 125.800104 270)
			(size 1.8034 0.508)
			(layers "B.Cu" "B.Mask" "B.Paste")
			(net "PVPP_KLM")
		)
		(pad "288" smd rect
			(at -4.59994 126.649988 270)
			(size 1.8034 0.508)
			(layers "B.Cu" "B.Mask" "B.Paste")
			(net "PVPP_KLM")
		)
	)
)
